# T6G (Grand Teton) — schematic netlist excerpt (pin names and nets, part order shuffled) for the footprints in the layout excerpt that follows; sources: Cadence DE-HDL packaged netlist, KiCad conversion of 04192023_DAF0TMB3IC0_F0TG_MB_C_brd_V02_OCP.brd

C2304  Q_CAP  22UF 4V 20% X6S  pkg C0402  page 73 : A = PVDDCR_CPU0_P1 ; B = GND
R757  Q_RES  4.7K 5% EMPTY  pkg 0402LF  page 83 : A = E1S_0_P3V3_EN ; B = P3V3_AUX

(kicad_pcb
	(version 20260206)
	(generator "pcbnew")
	(generator_version "10.0")
	(general
		(thickness 1.6)
		(legacy_teardrops no)
	)
	(paper "A4")
	(title_block
		(title "04192023_DAF0TMB3IC0_F0TG_MB_C_brd_V02_OCP.brd")
		(comment 1 "Grand Teton / footprints 6764-6765 of 8354")
	)
	(layers
		(0 "F.Cu" signal "TOP")
		(4 "In1.Cu" signal "GND")
		(6 "In2.Cu" signal "IN1")
		(8 "In3.Cu" signal "GND1")
		(10 "In4.Cu" signal "IN2")
		(12 "In5.Cu" signal "GND2")
		(14 "In6.Cu" signal "IN3")
		(16 "In7.Cu" signal "GND3")
		(18 "In8.Cu" signal "VCC")
		(20 "In9.Cu" signal "VCC1")
		(22 "In10.Cu" signal "GND4")
		(24 "In11.Cu" signal "IN4")
		(26 "In12.Cu" signal "GND5")
		(28 "In13.Cu" signal "IN5")
		(30 "In14.Cu" signal "GND6")
		(32 "In15.Cu" signal "IN6")
		(34 "In16.Cu" signal "GND7")
		(2 "B.Cu" signal "BOTTOM")
		(9 "F.Adhes" user "F.Adhesive")
		(11 "B.Adhes" user "B.Adhesive")
		(13 "F.Paste" user "Package Geometry/Pastemask Top")
		(15 "B.Paste" user "Package Geometry/Pastemask Bottom")
		(5 "F.SilkS" user "Ref Des/Silkscreen Top")
		(7 "B.SilkS" user "Ref Des/Silkscreen Bottom")
		(1 "F.Mask" user "Board Geometry/Soldermask Top")
		(3 "B.Mask" user "Board Geometry/Soldermask Bottom")
		(17 "Dwgs.User" user "User.Drawings")
		(19 "Cmts.User" user "User.Comments")
		(21 "Eco1.User" user "User.Eco1")
		(23 "Eco2.User" user "User.Eco2")
		(25 "Edge.Cuts" user "Board Geometry/Outline")
		(27 "Margin" user)
		(31 "F.CrtYd" user "Package Geometry/Place Bound Top")
		(29 "B.CrtYd" user "Package Geometry/Place Bound Bottom")
		(35 "F.Fab" user "Ref Des/Assembly Top")
		(33 "B.Fab" user "Ref Des/Assembly Bottom")
	)
	(footprint ""
		(layer "B.Cu")
		(at 208.748376 -120.944386 180)
		(property "Reference" "R757"
			(at 0 0 0)
			(layer "B.SilkS")
			(hide yes)
			(effects
				(font
					(size 1.27 1.27)
				)
				(justify mirror)
			)
		)
		(property "Value" ""
			(at 0 0 0)
			(layer "B.Fab")
			(effects
				(font
					(size 1.27 1.27)
				)
				(justify mirror)
			)
		)
		(duplicate_pad_numbers_are_jumpers no)
		(fp_line
			(start 0.7874 0.4064)
			(end 0.7874 -0.4064)
			(stroke
				(width 0.1524)
				(type default)
			)
			(layer "B.SilkS")
		)
		(fp_line
			(start 0.7874 -0.4064)
			(end -0.7874 -0.4064)
			(stroke
				(width 0.1524)
				(type default)
			)
			(layer "B.SilkS")
		)
		(fp_line
			(start -0.7874 0.4064)
			(end 0.7874 0.4064)
			(stroke
				(width 0.1524)
				(type default)
			)
			(layer "B.SilkS")
		)
		(fp_line
			(start -0.7874 -0.4064)
			(end -0.7874 0.4064)
			(stroke
				(width 0.1524)
				(type default)
			)
			(layer "B.SilkS")
		)
		(fp_line
			(start 0.67945 0.3048)
			(end 0.67945 -0.305054)
			(stroke
				(width 0.1)
				(type default)
			)
			(layer "B.Fab")
		)
		(fp_line
			(start 0.67945 -0.305054)
			(end 0.12065 -0.305054)
			(stroke
				(width 0.1)
				(type default)
			)
			(layer "B.Fab")
		)
		(fp_line
			(start 0.12065 0.3048)
			(end 0.67945 0.3048)
			(stroke
				(width 0.1)
				(type default)
			)
			(layer "B.Fab")
		)
		(fp_line
			(start 0.12065 0.2794)
			(end 0.12065 0.3048)
			(stroke
				(width 0.1)
				(type default)
			)
			(layer "B.Fab")
		)
		(fp_line
			(start 0.12065 -0.2794)
			(end -0.12065 -0.2794)
			(stroke
				(width 0.1)
				(type default)
			)
			(layer "B.Fab")
		)
		(fp_line
			(start 0.12065 -0.305054)
			(end 0.12065 -0.2794)
			(stroke
				(width 0.1)
				(type default)
			)
			(layer "B.Fab")
		)
		(fp_line
			(start -0.120396 0.3048)
			(end -0.120396 0.2794)
			(stroke
				(width 0.1)
				(type default)
			)
			(layer "B.Fab")
		)
		(fp_line
			(start -0.120396 0.2794)
			(end 0.12065 0.2794)
			(stroke
				(width 0.1)
				(type default)
			)
			(layer "B.Fab")
		)
		(fp_line
			(start -0.12065 -0.2794)
			(end -0.12065 -0.3048)
			(stroke
				(width 0.1)
				(type default)
			)
			(layer "B.Fab")
		)
		(fp_line
			(start -0.12065 -0.3048)
			(end -0.67945 -0.3048)
			(stroke
				(width 0.1)
				(type default)
			)
			(layer "B.Fab")
		)
		(fp_line
			(start -0.67945 0.3048)
			(end -0.120396 0.3048)
			(stroke
				(width 0.1)
				(type default)
			)
			(layer "B.Fab")
		)
		(fp_line
			(start -0.67945 -0.3048)
			(end -0.67945 0.3048)
			(stroke
				(width 0.1)
				(type default)
			)
			(layer "B.Fab")
		)
		(pad "1" smd circle
			(at 0.40005 0)
			(size 0 0)
			(layers "B.Cu" "B.Mask" "B.Paste")
			(net "E1S_0_P3V3_EN")
		)
		(pad "2" smd circle
			(at -0.40005 0)
			(size 0 0)
			(layers "B.Cu" "B.Mask" "B.Paste")
			(net "P3V3_AUX")
		)
	)
	(footprint ""
		(layer "B.Cu")
		(at 108.501434 -246.402352)
		(property "Reference" "C2304"
			(at 0 0 0)
			(layer "B.SilkS")
			(hide yes)
			(effects
				(font
					(size 1.27 1.27)
				)
				(justify mirror)
			)
		)
		(property "Value" ""
			(at 0 0 0)
			(layer "B.Fab")
			(effects
				(font
					(size 1.27 1.27)
				)
				(justify mirror)
			)
		)
		(duplicate_pad_numbers_are_jumpers no)
		(fp_line
			(start -0.7874 -0.4064)
			(end -0.7874 0.4064)
			(stroke
				(width 0.1524)
				(type default)
			)
			(layer "B.SilkS")
		)
		(fp_line
			(start -0.7874 0.4064)
			(end 0.7874 0.4064)
			(stroke
				(width 0.1524)
				(type default)
			)
			(layer "B.SilkS")
		)
		(fp_line
			(start 0.7874 -0.4064)
			(end -0.7874 -0.4064)
			(stroke
				(width 0.1524)
				(type default)
			)
			(layer "B.SilkS")
		)
		(fp_line
			(start 0.7874 0.4064)
			(end 0.7874 -0.4064)
			(stroke
				(width 0.1524)
				(type default)
			)
			(layer "B.SilkS")
		)
		(fp_line
			(start -0.67945 -0.3048)
			(end -0.67945 0.3048)
			(stroke
				(width 0.1)
				(type default)
			)
			(layer "B.Fab")
		)
		(fp_line
			(start -0.67945 0.3048)
			(end -0.120396 0.3048)
			(stroke
				(width 0.1)
				(type default)
			)
			(layer "B.Fab")
		)
		(fp_line
			(start -0.12065 -0.3048)
			(end -0.67945 -0.3048)
			(stroke
				(width 0.1)
				(type default)
			)
			(layer "B.Fab")
		)
		(fp_line
			(start -0.12065 -0.2794)
			(end -0.12065 -0.3048)
			(stroke
				(width 0.1)
				(type default)
			)
			(layer "B.Fab")
		)
		(fp_line
			(start -0.120396 0.2794)
			(end 0.12065 0.2794)
			(stroke
				(width 0.1)
				(type default)
			)
			(layer "B.Fab")
		)
		(fp_line
			(start -0.120396 0.3048)
			(end -0.120396 0.2794)
			(stroke
				(width 0.1)
				(type default)
			)
			(layer "B.Fab")
		)
		(fp_line
			(start 0.12065 -0.305054)
			(end 0.12065 -0.2794)
			(stroke
				(width 0.1)
				(type default)
			)
			(layer "B.Fab")
		)
		(fp_line
			(start 0.12065 -0.2794)
			(end -0.12065 -0.2794)
			(stroke
				(width 0.1)
				(type default)
			)
			(layer "B.Fab")
		)
		(fp_line
			(start 0.12065 0.2794)
			(end 0.12065 0.3048)
			(stroke
				(width 0.1)
				(type default)
			)
			(layer "B.Fab")
		)
		(fp_line
			(start 0.12065 0.3048)
			(end 0.67945 0.3048)
			(stroke
				(width 0.1)
				(type default)
			)
			(layer "B.Fab")
		)
		(fp_line
			(start 0.67945 -0.305054)
			(end 0.12065 -0.305054)
			(stroke
				(width 0.1)
				(type default)
			)
			(layer "B.Fab")
		)
		(fp_line
			(start 0.67945 0.3048)
			(end 0.67945 -0.305054)
			(stroke
				(width 0.1)
				(type default)
			)
			(layer "B.Fab")
		)
		(pad "1" smd circle
			(at 0.40005 0 180)
			(size 0 0)
			(layers "B.Cu" "B.Mask" "B.Paste")
			(net "PVDDCR_CPU0_P1")
		)
		(pad "2" smd circle
			(at -0.40005 0 180)
			(size 0 0)
			(layers "B.Cu" "B.Mask" "B.Paste")
			(net "GND")
		)
	)
)
